# T6G (Grand Teton) — schematic netlist excerpt (pin names and nets, part order shuffled) for the footprints in the layout excerpt that follows; sources: Cadence DE-HDL packaged netlist, KiCad conversion of 04192023_DAF0TMB3IC0_F0TG_MB_C_brd_V02_OCP.brd

R6209  Q_RES  10K 1% CHIP  pkg 0402LF  page 176 : A = USB_CPU0_HUB1_VBUS_US ; B = GND

U235  PCA9617ADP  IC  pkg TSSOP8_3XB  page 247
  VCCA  = P3V3_AUX
  SCLA  = SMB_OCP_V3_2_3V3AUX_SCL
  SDAA  = SMB_OCP_V3_2_3V3AUX_SDA
  GND  = GND
  EN  = HP_LVC3_OCP_V3_2_R_EN
  SDAB  = SMB_OCP_V3_2_3V3AUX_BUF_SDA
  SCLB  = SMB_OCP_V3_2_3V3AUX_BUF_SCL
  VCCB  = P3V3_OCP_V3_2

R624  Q_RES  51.1 1% EMPTY  pkg 0201LF  page 276 : A = CLK_100M_RETIMER_CPU0_P0_DP ; B = GND

(kicad_pcb
	(version 20260206)
	(generator "pcbnew")
	(generator_version "10.0")
	(general
		(thickness 1.6)
		(legacy_teardrops no)
	)
	(paper "A4")
	(title_block
		(title "04192023_DAF0TMB3IC0_F0TG_MB_C_brd_V02_OCP.brd")
		(comment 1 "Grand Teton / footprints 3259-3261 of 8354")
	)
	(layers
		(0 "F.Cu" signal "TOP")
		(4 "In1.Cu" signal "GND")
		(6 "In2.Cu" signal "IN1")
		(8 "In3.Cu" signal "GND1")
		(10 "In4.Cu" signal "IN2")
		(12 "In5.Cu" signal "GND2")
		(14 "In6.Cu" signal "IN3")
		(16 "In7.Cu" signal "GND3")
		(18 "In8.Cu" signal "VCC")
		(20 "In9.Cu" signal "VCC1")
		(22 "In10.Cu" signal "GND4")
		(24 "In11.Cu" signal "IN4")
		(26 "In12.Cu" signal "GND5")
		(28 "In13.Cu" signal "IN5")
		(30 "In14.Cu" signal "GND6")
		(32 "In15.Cu" signal "IN6")
		(34 "In16.Cu" signal "GND7")
		(2 "B.Cu" signal "BOTTOM")
		(9 "F.Adhes" user "F.Adhesive")
		(11 "B.Adhes" user "B.Adhesive")
		(13 "F.Paste" user "Package Geometry/Pastemask Top")
		(15 "B.Paste" user "Package Geometry/Pastemask Bottom")
		(5 "F.SilkS" user "Ref Des/Silkscreen Top")
		(7 "B.SilkS" user "Ref Des/Silkscreen Bottom")
		(1 "F.Mask" user "Board Geometry/Soldermask Top")
		(3 "B.Mask" user "Board Geometry/Soldermask Bottom")
		(17 "Dwgs.User" user "User.Drawings")
		(19 "Cmts.User" user "User.Comments")
		(21 "Eco1.User" user "User.Eco1")
		(23 "Eco2.User" user "User.Eco2")
		(25 "Edge.Cuts" user "Board Geometry/Outline")
		(27 "Margin" user)
		(31 "F.CrtYd" user "Package Geometry/Place Bound Top")
		(29 "B.CrtYd" user "Package Geometry/Place Bound Bottom")
		(35 "F.Fab" user "Ref Des/Assembly Top")
		(33 "B.Fab" user "Ref Des/Assembly Bottom")
	)
	(footprint ""
		(layer "F.Cu")
		(at 147.53844 -38.95344)
		(property "Reference" "U235"
			(at -1.44272 2.425192 0)
			(unlocked yes)
			(layer "F.SilkS")
			(effects
				(font
					(size 0.7874 0.5842)
					(thickness 0.1524)
				)
				(justify left)
			)
		)
		(property "Value" ""
			(at 0 0 0)
			(layer "F.Fab")
			(effects
				(font
					(size 1.27 1.27)
				)
			)
		)
		(duplicate_pad_numbers_are_jumpers no)
		(fp_line
			(start -1.463548 -1.549908)
			(end -0.787908 -1.549908)
			(stroke
				(width 0.1524)
				(type default)
			)
			(layer "F.SilkS")
		)
		(fp_line
			(start -1.463548 1.549908)
			(end -1.463548 -1.549908)
			(stroke
				(width 0.1524)
				(type default)
			)
			(layer "F.SilkS")
		)
		(fp_line
			(start -0.787908 -1.549908)
			(end 0 -0.762)
			(stroke
				(width 0.1524)
				(type default)
			)
			(layer "F.SilkS")
		)
		(fp_line
			(start 0 -0.762)
			(end 0.762 -1.549908)
			(stroke
				(width 0.1524)
				(type default)
			)
			(layer "F.SilkS")
		)
		(fp_line
			(start 0.762 -1.549908)
			(end 1.463548 -1.549908)
			(stroke
				(width 0.1524)
				(type default)
			)
			(layer "F.SilkS")
		)
		(fp_line
			(start 1.463548 -1.549908)
			(end 1.463548 1.549908)
			(stroke
				(width 0.1524)
				(type default)
			)
			(layer "F.SilkS")
		)
		(fp_line
			(start 1.463548 1.549908)
			(end -1.463548 1.549908)
			(stroke
				(width 0.1524)
				(type default)
			)
			(layer "F.SilkS")
		)
		(fp_poly
			(pts
				(xy -3.062732 -1.753616) (xy -2.624582 -2.191766) (xy -2.40538 -1.534414)
			)
			(stroke
				(width 0)
				(type default)
			)
			(fill yes)
			(layer "F.SilkS")
		)
		(fp_line
			(start -1.549908 -1.549908)
			(end 1.549908 -1.549908)
			(stroke
				(width 0.1)
				(type default)
			)
			(layer "F.Fab")
		)
		(fp_line
			(start -1.549908 1.549908)
			(end -1.549908 -1.549908)
			(stroke
				(width 0.1)
				(type default)
			)
			(layer "F.Fab")
		)
		(fp_line
			(start 1.549908 -1.549908)
			(end 1.549908 1.549908)
			(stroke
				(width 0.1)
				(type default)
			)
			(layer "F.Fab")
		)
		(fp_line
			(start 1.549908 1.549908)
			(end -1.549908 1.549908)
			(stroke
				(width 0.1)
				(type default)
			)
			(layer "F.Fab")
		)
		(fp_poly
			(pts
				(xy -3.4798 -1.359916) (xy -2.86004 -1.050036) (xy -3.4798 -0.740156)
			)
			(stroke
				(width 0)
				(type default)
			)
			(fill yes)
			(layer "F.Fab")
		)
		(pad "1" smd rect
			(at -2.175002 -1.050036 90)
			(size 0.6096 1.1684)
			(layers "F.Cu" "F.Mask" "F.Paste")
			(net "P3V3_AUX")
		)
		(pad "2" smd rect
			(at -2.175002 -0.32512 90)
			(size 0.4318 1.1684)
			(layers "F.Cu" "F.Mask" "F.Paste")
			(net "SMB_OCP_V3_2_3V3AUX_SCL")
		)
		(pad "3" smd rect
			(at -2.175002 0.32512 90)
			(size 0.4318 1.1684)
			(layers "F.Cu" "F.Mask" "F.Paste")
			(net "SMB_OCP_V3_2_3V3AUX_SDA")
		)
		(pad "4" smd rect
			(at -2.175002 1.050036 90)
			(size 0.6096 1.1684)
			(layers "F.Cu" "F.Mask" "F.Paste")
			(net "GND")
		)
		(pad "5" smd rect
			(at 2.175002 1.050036 90)
			(size 0.6096 1.1684)
			(layers "F.Cu" "F.Mask" "F.Paste")
			(net "HP_LVC3_OCP_V3_2_R_EN")
		)
		(pad "6" smd rect
			(at 2.175002 0.32512 90)
			(size 0.4318 1.1684)
			(layers "F.Cu" "F.Mask" "F.Paste")
			(net "SMB_OCP_V3_2_3V3AUX_BUF_SDA")
		)
		(pad "7" smd rect
			(at 2.175002 -0.32512 90)
			(size 0.4318 1.1684)
			(layers "F.Cu" "F.Mask" "F.Paste")
			(net "SMB_OCP_V3_2_3V3AUX_BUF_SCL")
		)
		(pad "8" smd rect
			(at 2.175002 -1.050036 90)
			(size 0.6096 1.1684)
			(layers "F.Cu" "F.Mask" "F.Paste")
			(net "P3V3_OCP_V3_2")
		)
	)
	(footprint ""
		(layer "F.Cu")
		(at 299.543724 -396.412974 90)
		(property "Reference" "R624"
			(at 0 0 90)
			(layer "F.SilkS")
			(hide yes)
			(effects
				(font
					(size 1.27 1.27)
				)
			)
		)
		(property "Value" ""
			(at 0 0 90)
			(layer "F.Fab")
			(effects
				(font
					(size 1.27 1.27)
				)
			)
		)
		(duplicate_pad_numbers_are_jumpers no)
		(fp_line
			(start 0.32512 -0.175006)
			(end 0.32512 0.175006)
			(stroke
				(width 0.1)
				(type default)
			)
			(layer "F.Fab")
		)
		(fp_line
			(start -0.32512 -0.175006)
			(end 0.32512 -0.175006)
			(stroke
				(width 0.1)
				(type default)
			)
			(layer "F.Fab")
		)
		(fp_line
			(start 0.32512 0.175006)
			(end -0.32512 0.175006)
			(stroke
				(width 0.1)
				(type default)
			)
			(layer "F.Fab")
		)
		(fp_line
			(start -0.32512 0.175006)
			(end -0.32512 -0.175006)
			(stroke
				(width 0.1)
				(type default)
			)
			(layer "F.Fab")
		)
		(pad "1" smd rect
			(at -0.2667 0 90)
			(size 0.3048 0.381)
			(layers "F.Cu" "F.Mask" "F.Paste")
			(net "CLK_100M_RETIMER_CPU0_P0_DP")
		)
		(pad "2" smd rect
			(at 0.2667 0 270)
			(size 0.3048 0.381)
			(layers "F.Cu" "F.Mask" "F.Paste")
			(net "GND")
		)
	)
	(footprint ""
		(layer "F.Cu")
		(at 140.420344 -38.796468)
		(property "Reference" "R6209"
			(at 0 0 0)
			(layer "F.SilkS")
			(hide yes)
			(effects
				(font
					(size 1.27 1.27)
				)
			)
		)
		(property "Value" ""
			(at 0 0 0)
			(layer "F.Fab")
			(effects
				(font
					(size 1.27 1.27)
				)
			)
		)
		(duplicate_pad_numbers_are_jumpers no)
		(fp_line
			(start -0.7874 -0.4064)
			(end 0.7874 -0.4064)
			(stroke
				(width 0.1524)
				(type default)
			)
			(layer "F.SilkS")
		)
		(fp_line
			(start -0.7874 0.4064)
			(end -0.7874 -0.4064)
			(stroke
				(width 0.1524)
				(type default)
			)
			(layer "F.SilkS")
		)
		(fp_line
			(start 0.7874 -0.4064)
			(end 0.7874 0.4064)
			(stroke
				(width 0.1524)
				(type default)
			)
			(layer "F.SilkS")
		)
		(fp_line
			(start 0.7874 0.4064)
			(end -0.7874 0.4064)
			(stroke
				(width 0.1524)
				(type default)
			)
			(layer "F.SilkS")
		)
		(fp_line
			(start -0.67945 -0.305054)
			(end -0.12065 -0.305054)
			(stroke
				(width 0.1)
				(type default)
			)
			(layer "F.Fab")
		)
		(fp_line
			(start -0.67945 0.3048)
			(end -0.67945 -0.305054)
			(stroke
				(width 0.1)
				(type default)
			)
			(layer "F.Fab")
		)
		(fp_line
			(start -0.12065 -0.305054)
			(end -0.12065 -0.2794)
			(stroke
				(width 0.1)
				(type default)
			)
			(layer "F.Fab")
		)
		(fp_line
			(start -0.12065 -0.2794)
			(end 0.12065 -0.2794)
			(stroke
				(width 0.1)
				(type default)
			)
			(layer "F.Fab")
		)
		(fp_line
			(start -0.12065 0.2794)
			(end -0.12065 0.3048)
			(stroke
				(width 0.1)
				(type default)
			)
			(layer "F.Fab")
		)
		(fp_line
			(start -0.12065 0.3048)
			(end -0.67945 0.3048)
			(stroke
				(width 0.1)
				(type default)
			)
			(layer "F.Fab")
		)
		(fp_line
			(start 0.120396 0.2794)
			(end -0.12065 0.2794)
			(stroke
				(width 0.1)
				(type default)
			)
			(layer "F.Fab")
		)
		(fp_line
			(start 0.120396 0.3048)
			(end 0.120396 0.2794)
			(stroke
				(width 0.1)
				(type default)
			)
			(layer "F.Fab")
		)
		(fp_line
			(start 0.12065 -0.3048)
			(end 0.67945 -0.3048)
			(stroke
				(width 0.1)
				(type default)
			)
			(layer "F.Fab")
		)
		(fp_line
			(start 0.12065 -0.2794)
			(end 0.12065 -0.3048)
			(stroke
				(width 0.1)
				(type default)
			)
			(layer "F.Fab")
		)
		(fp_line
			(start 0.67945 -0.3048)
			(end 0.67945 0.3048)
			(stroke
				(width 0.1)
				(type default)
			)
			(layer "F.Fab")
		)
		(fp_line
			(start 0.67945 0.3048)
			(end 0.120396 0.3048)
			(stroke
				(width 0.1)
				(type default)
			)
			(layer "F.Fab")
		)
		(pad "1" smd circle
			(at -0.40005 0)
			(size 0 0)
			(layers "F.Cu" "F.Mask" "F.Paste")
			(net "USB_CPU0_HUB1_VBUS_US")
		)
		(pad "2" smd circle
			(at 0.40005 0)
			(size 0 0)
			(layers "F.Cu" "F.Mask" "F.Paste")
			(net "GND")
		)
	)
)
